(kicad_pcb
	(version 20260206)
	(generator "pcbnew")
	(generator_version "10.0")
	(general
		(thickness 1.6)
		(legacy_teardrops no)
	)
	(paper "A4")
	(title_block
		(title "panther-plus-userver — 13130-1b_20150205.brd")
		(comment 1 "Honey Badger (Wiwynn) / footprint 1214 of 1509 (DIMM3), pads 30-36 of 210")
	)
	(layers
		(0 "F.Cu" signal "TOP")
		(4 "In1.Cu" signal "L2")
		(6 "In2.Cu" signal "L3")
		(8 "In3.Cu" signal "L4")
		(10 "In4.Cu" signal "L5")
		(12 "In5.Cu" signal "L6")
		(14 "In6.Cu" signal "L7")
		(16 "In7.Cu" signal "L8")
		(18 "In8.Cu" signal "L9")
		(20 "In9.Cu" signal "L10")
		(22 "In10.Cu" signal "L11")
		(2 "B.Cu" signal "BOTTOM")
		(9 "F.Adhes" user "F.Adhesive")
		(11 "B.Adhes" user "B.Adhesive")
		(13 "F.Paste" user "Package Geometry/Pastemask Top")
		(15 "B.Paste" user "Package Geometry/Pastemask Bottom")
		(5 "F.SilkS" user "Ref Des/Silkscreen Top")
		(7 "B.SilkS" user "Ref Des/Silkscreen Bottom")
		(1 "F.Mask" user "Board Geometry/Soldermask Top")
		(3 "B.Mask" user "Board Geometry/Soldermask Bottom")
		(17 "Dwgs.User" user "User.Drawings")
		(19 "Cmts.User" user "User.Comments")
		(21 "Eco1.User" user "User.Eco1")
		(23 "Eco2.User" user "User.Eco2")
		(25 "Edge.Cuts" user "Board Geometry/Outline")
		(27 "Margin" user)
		(31 "F.CrtYd" user "Package Geometry/Place Bound Top")
		(29 "B.CrtYd" user "Package Geometry/Place Bound Bottom")
		(35 "F.Fab" user "Ref Des/Assembly Top")
		(33 "B.Fab" user "Ref Des/Assembly Bottom")
	)
	(footprint ""
		(layer "B.Cu")
		(at 159.999934 -5.790692)
		(property "Reference" "DIMM3"
			(at 0 0 0)
			(layer "B.SilkS")
			(hide yes)
			(effects
				(font
					(size 1.27 1.27)
				)
				(justify mirror)
			)
		)
		(property "Value" "DDR3-204P-142-COLAY-1-GP-U"
			(at 41.312338 -16.676878 0)
			(unlocked yes)
			(layer "B.Fab")
			(hide yes)
			(effects
				(font
					(size 1.016 1.016)
					(thickness 0.1524)
				)
				(justify mirror)
			)
		)
		(property "Device Type" "AS0A626-J8R6-7H-COLAY-1"
			(at 41.312338 -18.200878 0)
			(unlocked yes)
			(layer "B.Fab")
			(hide yes)
			(effects
				(font
					(size 1.016 1.016)
					(thickness 0.1524)
				)
				(justify mirror)
			)
		)
		(duplicate_pad_numbers_are_jumpers no)
		(pad "28" smd custom
			(at -23.550118 4.100068 180)
			(size 0.1143 0.1143)
			(layers "B.Cu" "B.Mask" "B.Paste")
			(net "GND")
			(options
				(clearance outline)
				(anchor circle)
			)
			(primitives
				(gr_poly
					(pts
						(xy 0 -0.9017) (xy -0.03175 -0.89916) (xy -0.0635 -0.889) (xy -0.09144 -0.87376) (xy -0.11684 -0.85344)
						(xy -0.13716 -0.82804) (xy -0.1524 -0.8001) (xy -0.16256 -0.76835) (xy -0.1651 -0.7366) (xy -0.1651 -0.11938)
						(xy -0.17272 -0.11176) (xy -0.19812 -0.0762) (xy -0.2032 -0.06604) (xy -0.20701 -0.05715) (xy -0.21209 -0.04699)
						(xy -0.2159 -0.03683) (xy -0.21844 -0.02667) (xy -0.22225 -0.01524) (xy -0.22352 -0.00508) (xy -0.22606 0.00508)
						(xy -0.22733 0.01651) (xy -0.22733 0.02667) (xy -0.2286 0.0381) (xy -0.22733 0.04953) (xy -0.22733 0.05969)
						(xy -0.22606 0.07112) (xy -0.22352 0.08128) (xy -0.22225 0.09144) (xy -0.21844 0.10287) (xy -0.2159 0.11303)
						(xy -0.21209 0.12319) (xy -0.20701 0.13335) (xy -0.2032 0.14224) (xy -0.19812 0.1524) (xy -0.17272 0.18796)
						(xy -0.1651 0.19558) (xy -0.1651 0.7366) (xy -0.16256 0.76835) (xy -0.1524 0.8001) (xy -0.13716 0.82804)
						(xy -0.11684 0.85344) (xy -0.09144 0.87376) (xy -0.0635 0.889) (xy -0.03175 0.89916) (xy 0 0.9017)
						(xy 0.03175 0.89916) (xy 0.0635 0.889) (xy 0.09144 0.87376) (xy 0.11684 0.85344) (xy 0.13716 0.82804)
						(xy 0.1524 0.8001) (xy 0.16256 0.76835) (xy 0.1651 0.7366) (xy 0.1651 0.19685) (xy 0.17272 0.18923)
						(xy 0.17907 0.18034) (xy 0.18669 0.17145) (xy 0.19177 0.16256) (xy 0.19812 0.15367) (xy 0.20828 0.13335)
						(xy 0.21971 0.10287) (xy 0.22225 0.09271) (xy 0.22479 0.08128) (xy 0.22606 0.07112) (xy 0.2286 0.05969)
						(xy 0.2286 0.01651) (xy 0.22606 0.00508) (xy 0.22479 -0.00508) (xy 0.22225 -0.01651) (xy 0.21971 -0.02667)
						(xy 0.20828 -0.05715) (xy 0.19812 -0.07747) (xy 0.19177 -0.08636) (xy 0.18669 -0.09525) (xy 0.17907 -0.10414)
						(xy 0.17272 -0.11303) (xy 0.1651 -0.12065) (xy 0.1651 -0.7366) (xy 0.16256 -0.76835) (xy 0.1524 -0.8001)
						(xy 0.13716 -0.82804) (xy 0.11684 -0.85344) (xy 0.09144 -0.87376) (xy 0.0635 -0.889) (xy 0.03175 -0.89916)
					)
					(width 0)
					(fill yes)
				)
			)
		)
		(pad "29" smd custom
			(at -23.24989 -4.100068 180)
			(size 0.1143 0.1143)
			(layers "B.Cu" "B.Mask" "B.Paste")
			(net "GND")
			(options
				(clearance outline)
				(anchor circle)
			)
			(primitives
				(gr_poly
					(pts
						(xy 0 -0.9017) (xy -0.03175 -0.89916) (xy -0.0635 -0.889) (xy -0.09144 -0.87376) (xy -0.11684 -0.85344)
						(xy -0.13716 -0.82804) (xy -0.1524 -0.8001) (xy -0.16256 -0.76835) (xy -0.1651 -0.7366) (xy -0.1651 -0.44958)
						(xy -0.17272 -0.44196) (xy -0.19812 -0.4064) (xy -0.2032 -0.39624) (xy -0.20701 -0.38735) (xy -0.21209 -0.37719)
						(xy -0.2159 -0.36703) (xy -0.21844 -0.35687) (xy -0.22225 -0.34544) (xy -0.22352 -0.33528) (xy -0.22606 -0.32512)
						(xy -0.22733 -0.31369) (xy -0.22733 -0.30353) (xy -0.2286 -0.2921) (xy -0.22733 -0.28067) (xy -0.22733 -0.27051)
						(xy -0.22606 -0.25908) (xy -0.22352 -0.24892) (xy -0.22225 -0.23876) (xy -0.21844 -0.22733) (xy -0.2159 -0.21717)
						(xy -0.21209 -0.20701) (xy -0.20701 -0.19685) (xy -0.2032 -0.18796) (xy -0.19812 -0.1778) (xy -0.17272 -0.14224)
						(xy -0.1651 -0.13462) (xy -0.1651 0.7366) (xy -0.16256 0.76835) (xy -0.1524 0.8001) (xy -0.13716 0.82804)
						(xy -0.11684 0.85344) (xy -0.09144 0.87376) (xy -0.0635 0.889) (xy -0.03175 0.89916) (xy 0 0.9017)
						(xy 0.03175 0.89916) (xy 0.0635 0.889) (xy 0.09144 0.87376) (xy 0.11684 0.85344) (xy 0.13716 0.82804)
						(xy 0.1524 0.8001) (xy 0.16256 0.76835) (xy 0.1651 0.7366) (xy 0.1651 -0.13462) (xy 0.17272 -0.14224)
						(xy 0.19812 -0.1778) (xy 0.2032 -0.18796) (xy 0.20701 -0.19685) (xy 0.21209 -0.20701) (xy 0.2159 -0.21717)
						(xy 0.21844 -0.22733) (xy 0.22225 -0.23876) (xy 0.22352 -0.24892) (xy 0.22606 -0.25908) (xy 0.22733 -0.27051)
						(xy 0.22733 -0.28067) (xy 0.2286 -0.2921) (xy 0.22733 -0.30353) (xy 0.22733 -0.31369) (xy 0.22606 -0.32512)
						(xy 0.22352 -0.33528) (xy 0.22225 -0.34544) (xy 0.21844 -0.35687) (xy 0.2159 -0.36703) (xy 0.21209 -0.37719)
						(xy 0.20701 -0.38735) (xy 0.2032 -0.39624) (xy 0.19812 -0.4064) (xy 0.17272 -0.44196) (xy 0.1651 -0.44958)
						(xy 0.1651 -0.7366) (xy 0.16256 -0.76835) (xy 0.1524 -0.8001) (xy 0.13716 -0.82804) (xy 0.11684 -0.85344)
						(xy 0.09144 -0.87376) (xy 0.0635 -0.889) (xy 0.03175 -0.89916)
					)
					(width 0)
					(fill yes)
				)
			)
		)
		(pad "30" smd custom
			(at -22.949916 4.100068 180)
			(size 0.1143 0.1143)
			(layers "B.Cu" "B.Mask" "B.Paste")
			(net "M_B_RESET#")
			(options
				(clearance outline)
				(anchor circle)
			)
			(primitives
				(gr_poly
					(pts
						(xy 0 -0.9017) (xy -0.03175 -0.89916) (xy -0.0635 -0.889) (xy -0.09144 -0.87376) (xy -0.11684 -0.85344)
						(xy -0.13716 -0.82804) (xy -0.1524 -0.8001) (xy -0.16256 -0.76835) (xy -0.1651 -0.7366) (xy -0.1651 0.13462)
						(xy -0.17272 0.14224) (xy -0.19812 0.1778) (xy -0.2032 0.18796) (xy -0.20701 0.19685) (xy -0.21209 0.20701)
						(xy -0.2159 0.21717) (xy -0.21844 0.22733) (xy -0.22225 0.23876) (xy -0.22352 0.24892) (xy -0.22606 0.25908)
						(xy -0.22733 0.27051) (xy -0.22733 0.28067) (xy -0.2286 0.2921) (xy -0.22733 0.30353) (xy -0.22733 0.31369)
						(xy -0.22606 0.32512) (xy -0.22352 0.33528) (xy -0.22225 0.34544) (xy -0.21844 0.35687) (xy -0.2159 0.36703)
						(xy -0.21209 0.37719) (xy -0.20701 0.38735) (xy -0.2032 0.39624) (xy -0.19812 0.4064) (xy -0.17272 0.44196)
						(xy -0.1651 0.44958) (xy -0.1651 0.7366) (xy -0.16256 0.76835) (xy -0.1524 0.8001) (xy -0.13716 0.82804)
						(xy -0.11684 0.85344) (xy -0.09144 0.87376) (xy -0.0635 0.889) (xy -0.03175 0.89916) (xy 0 0.9017)
						(xy 0.03175 0.89916) (xy 0.0635 0.889) (xy 0.09144 0.87376) (xy 0.11684 0.85344) (xy 0.13716 0.82804)
						(xy 0.1524 0.8001) (xy 0.16256 0.76835) (xy 0.1651 0.7366) (xy 0.1651 0.44958) (xy 0.17272 0.44196)
						(xy 0.19812 0.4064) (xy 0.2032 0.39624) (xy 0.20701 0.38735) (xy 0.21209 0.37719) (xy 0.2159 0.36703)
						(xy 0.21844 0.35687) (xy 0.22225 0.34544) (xy 0.22352 0.33528) (xy 0.22606 0.32512) (xy 0.22733 0.31369)
						(xy 0.22733 0.30353) (xy 0.2286 0.2921) (xy 0.22733 0.28067) (xy 0.22733 0.27051) (xy 0.22606 0.25908)
						(xy 0.22352 0.24892) (xy 0.22225 0.23876) (xy 0.21844 0.22733) (xy 0.2159 0.21717) (xy 0.21209 0.20701)
						(xy 0.20701 0.19685) (xy 0.2032 0.18796) (xy 0.19812 0.1778) (xy 0.17272 0.14224) (xy 0.1651 0.13462)
						(xy 0.1651 -0.7366) (xy 0.16256 -0.76835) (xy 0.1524 -0.8001) (xy 0.13716 -0.82804) (xy 0.11684 -0.85344)
						(xy 0.09144 -0.87376) (xy 0.0635 -0.889) (xy 0.03175 -0.89916)
					)
					(width 0)
					(fill yes)
				)
			)
		)
		(pad "31" smd custom
			(at -22.649942 -4.100068 180)
			(size 0.1143 0.1143)
			(layers "B.Cu" "B.Mask" "B.Paste")
			(net "M_B_DQ10")
			(options
				(clearance outline)
				(anchor circle)
			)
			(primitives
				(gr_poly
					(pts
						(xy 0 -0.9017) (xy -0.03175 -0.89916) (xy -0.0635 -0.889) (xy -0.09144 -0.87376) (xy -0.11684 -0.85344)
						(xy -0.13716 -0.82804) (xy -0.1524 -0.8001) (xy -0.16256 -0.76835) (xy -0.1651 -0.7366) (xy -0.1651 -0.19685)
						(xy -0.17272 -0.18923) (xy -0.17907 -0.18034) (xy -0.18669 -0.17145) (xy -0.19177 -0.16256) (xy -0.19812 -0.15367)
						(xy -0.20828 -0.13335) (xy -0.21971 -0.10287) (xy -0.22225 -0.09271) (xy -0.22479 -0.08128) (xy -0.22606 -0.07112)
						(xy -0.2286 -0.05969) (xy -0.2286 -0.01651) (xy -0.22606 -0.00508) (xy -0.22479 0.00508) (xy -0.22225 0.01651)
						(xy -0.21971 0.02667) (xy -0.20828 0.05715) (xy -0.19812 0.07747) (xy -0.19177 0.08636) (xy -0.18669 0.09525)
						(xy -0.17907 0.10414) (xy -0.17272 0.11303) (xy -0.1651 0.12065) (xy -0.1651 0.7366) (xy -0.16256 0.76835)
						(xy -0.1524 0.8001) (xy -0.13716 0.82804) (xy -0.11684 0.85344) (xy -0.09144 0.87376) (xy -0.0635 0.889)
						(xy -0.03175 0.89916) (xy 0 0.9017) (xy 0.03175 0.89916) (xy 0.0635 0.889) (xy 0.09144 0.87376)
						(xy 0.11684 0.85344) (xy 0.13716 0.82804) (xy 0.1524 0.8001) (xy 0.16256 0.76835) (xy 0.1651 0.7366)
						(xy 0.1651 0.11938) (xy 0.17272 0.11176) (xy 0.19812 0.0762) (xy 0.2032 0.06604) (xy 0.20701 0.05715)
						(xy 0.21209 0.04699) (xy 0.2159 0.03683) (xy 0.21844 0.02667) (xy 0.22225 0.01524) (xy 0.22352 0.00508)
						(xy 0.22606 -0.00508) (xy 0.22733 -0.01651) (xy 0.22733 -0.02667) (xy 0.2286 -0.0381) (xy 0.22733 -0.04953)
						(xy 0.22733 -0.05969) (xy 0.22606 -0.07112) (xy 0.22352 -0.08128) (xy 0.22225 -0.09144) (xy 0.21844 -0.10287)
						(xy 0.2159 -0.11303) (xy 0.21209 -0.12319) (xy 0.20701 -0.13335) (xy 0.2032 -0.14224) (xy 0.19812 -0.1524)
						(xy 0.17272 -0.18796) (xy 0.1651 -0.19558) (xy 0.1651 -0.7366) (xy 0.16256 -0.76835) (xy 0.1524 -0.8001)
						(xy 0.13716 -0.82804) (xy 0.11684 -0.85344) (xy 0.09144 -0.87376) (xy 0.0635 -0.889) (xy 0.03175 -0.89916)
					)
					(width 0)
					(fill yes)
				)
			)
		)
		(pad "32" smd custom
			(at -22.349968 4.100068 180)
			(size 0.1143 0.1143)
			(layers "B.Cu" "B.Mask" "B.Paste")
			(net "GND")
			(options
				(clearance outline)
				(anchor circle)
			)
			(primitives
				(gr_poly
					(pts
						(xy 0 -0.9017) (xy -0.03175 -0.89916) (xy -0.0635 -0.889) (xy -0.09144 -0.87376) (xy -0.11684 -0.85344)
						(xy -0.13716 -0.82804) (xy -0.1524 -0.8001) (xy -0.16256 -0.76835) (xy -0.1651 -0.7366) (xy -0.1651 -0.11938)
						(xy -0.17272 -0.11176) (xy -0.19812 -0.0762) (xy -0.2032 -0.06604) (xy -0.20701 -0.05715) (xy -0.21209 -0.04699)
						(xy -0.2159 -0.03683) (xy -0.21844 -0.02667) (xy -0.22225 -0.01524) (xy -0.22352 -0.00508) (xy -0.22606 0.00508)
						(xy -0.22733 0.01651) (xy -0.22733 0.02667) (xy -0.2286 0.0381) (xy -0.22733 0.04953) (xy -0.22733 0.05969)
						(xy -0.22606 0.07112) (xy -0.22352 0.08128) (xy -0.22225 0.09144) (xy -0.21844 0.10287) (xy -0.2159 0.11303)
						(xy -0.21209 0.12319) (xy -0.20701 0.13335) (xy -0.2032 0.14224) (xy -0.19812 0.1524) (xy -0.17272 0.18796)
						(xy -0.1651 0.19558) (xy -0.1651 0.7366) (xy -0.16256 0.76835) (xy -0.1524 0.8001) (xy -0.13716 0.82804)
						(xy -0.11684 0.85344) (xy -0.09144 0.87376) (xy -0.0635 0.889) (xy -0.03175 0.89916) (xy 0 0.9017)
						(xy 0.03175 0.89916) (xy 0.0635 0.889) (xy 0.09144 0.87376) (xy 0.11684 0.85344) (xy 0.13716 0.82804)
						(xy 0.1524 0.8001) (xy 0.16256 0.76835) (xy 0.1651 0.7366) (xy 0.1651 0.19685) (xy 0.17272 0.18923)
						(xy 0.17907 0.18034) (xy 0.18669 0.17145) (xy 0.19177 0.16256) (xy 0.19812 0.15367) (xy 0.20828 0.13335)
						(xy 0.21971 0.10287) (xy 0.22225 0.09271) (xy 0.22479 0.08128) (xy 0.22606 0.07112) (xy 0.2286 0.05969)
						(xy 0.2286 0.01651) (xy 0.22606 0.00508) (xy 0.22479 -0.00508) (xy 0.22225 -0.01651) (xy 0.21971 -0.02667)
						(xy 0.20828 -0.05715) (xy 0.19812 -0.07747) (xy 0.19177 -0.08636) (xy 0.18669 -0.09525) (xy 0.17907 -0.10414)
						(xy 0.17272 -0.11303) (xy 0.1651 -0.12065) (xy 0.1651 -0.7366) (xy 0.16256 -0.76835) (xy 0.1524 -0.8001)
						(xy 0.13716 -0.82804) (xy 0.11684 -0.85344) (xy 0.09144 -0.87376) (xy 0.0635 -0.889) (xy 0.03175 -0.89916)
					)
					(width 0)
					(fill yes)
				)
			)
		)
		(pad "33" smd custom
			(at -22.049994 -4.100068 180)
			(size 0.1143 0.1143)
			(layers "B.Cu" "B.Mask" "B.Paste")
			(net "M_B_DQ11")
			(options
				(clearance outline)
				(anchor circle)
			)
			(primitives
				(gr_poly
					(pts
						(xy 0 -0.9017) (xy -0.03175 -0.89916) (xy -0.0635 -0.889) (xy -0.09144 -0.87376) (xy -0.11684 -0.85344)
						(xy -0.13716 -0.82804) (xy -0.1524 -0.8001) (xy -0.16256 -0.76835) (xy -0.1651 -0.7366) (xy -0.1651 -0.44958)
						(xy -0.17272 -0.44196) (xy -0.19812 -0.4064) (xy -0.2032 -0.39624) (xy -0.20701 -0.38735) (xy -0.21209 -0.37719)
						(xy -0.2159 -0.36703) (xy -0.21844 -0.35687) (xy -0.22225 -0.34544) (xy -0.22352 -0.33528) (xy -0.22606 -0.32512)
						(xy -0.22733 -0.31369) (xy -0.22733 -0.30353) (xy -0.2286 -0.2921) (xy -0.22733 -0.28067) (xy -0.22733 -0.27051)
						(xy -0.22606 -0.25908) (xy -0.22352 -0.24892) (xy -0.22225 -0.23876) (xy -0.21844 -0.22733) (xy -0.2159 -0.21717)
						(xy -0.21209 -0.20701) (xy -0.20701 -0.19685) (xy -0.2032 -0.18796) (xy -0.19812 -0.1778) (xy -0.17272 -0.14224)
						(xy -0.1651 -0.13462) (xy -0.1651 0.7366) (xy -0.16256 0.76835) (xy -0.1524 0.8001) (xy -0.13716 0.82804)
						(xy -0.11684 0.85344) (xy -0.09144 0.87376) (xy -0.0635 0.889) (xy -0.03175 0.89916) (xy 0 0.9017)
						(xy 0.03175 0.89916) (xy 0.0635 0.889) (xy 0.09144 0.87376) (xy 0.11684 0.85344) (xy 0.13716 0.82804)
						(xy 0.1524 0.8001) (xy 0.16256 0.76835) (xy 0.1651 0.7366) (xy 0.1651 -0.13462) (xy 0.17272 -0.14224)
						(xy 0.19812 -0.1778) (xy 0.2032 -0.18796) (xy 0.20701 -0.19685) (xy 0.21209 -0.20701) (xy 0.2159 -0.21717)
						(xy 0.21844 -0.22733) (xy 0.22225 -0.23876) (xy 0.22352 -0.24892) (xy 0.22606 -0.25908) (xy 0.22733 -0.27051)
						(xy 0.22733 -0.28067) (xy 0.2286 -0.2921) (xy 0.22733 -0.30353) (xy 0.22733 -0.31369) (xy 0.22606 -0.32512)
						(xy 0.22352 -0.33528) (xy 0.22225 -0.34544) (xy 0.21844 -0.35687) (xy 0.2159 -0.36703) (xy 0.21209 -0.37719)
						(xy 0.20701 -0.38735) (xy 0.2032 -0.39624) (xy 0.19812 -0.4064) (xy 0.17272 -0.44196) (xy 0.1651 -0.44958)
						(xy 0.1651 -0.7366) (xy 0.16256 -0.76835) (xy 0.1524 -0.8001) (xy 0.13716 -0.82804) (xy 0.11684 -0.85344)
						(xy 0.09144 -0.87376) (xy 0.0635 -0.889) (xy 0.03175 -0.89916)
					)
					(width 0)
					(fill yes)
				)
			)
		)
		(pad "34" smd custom
			(at -21.75002 4.100068 180)
			(size 0.1143 0.1143)
			(layers "B.Cu" "B.Mask" "B.Paste")
			(net "M_B_DQ14")
			(options
				(clearance outline)
				(anchor circle)
			)
			(primitives
				(gr_poly
					(pts
						(xy 0 -0.9017) (xy -0.03175 -0.89916) (xy -0.0635 -0.889) (xy -0.09144 -0.87376) (xy -0.11684 -0.85344)
						(xy -0.13716 -0.82804) (xy -0.1524 -0.8001) (xy -0.16256 -0.76835) (xy -0.1651 -0.7366) (xy -0.1651 0.13462)
						(xy -0.17272 0.14224) (xy -0.19812 0.1778) (xy -0.2032 0.18796) (xy -0.20701 0.19685) (xy -0.21209 0.20701)
						(xy -0.2159 0.21717) (xy -0.21844 0.22733) (xy -0.22225 0.23876) (xy -0.22352 0.24892) (xy -0.22606 0.25908)
						(xy -0.22733 0.27051) (xy -0.22733 0.28067) (xy -0.2286 0.2921) (xy -0.22733 0.30353) (xy -0.22733 0.31369)
						(xy -0.22606 0.32512) (xy -0.22352 0.33528) (xy -0.22225 0.34544) (xy -0.21844 0.35687) (xy -0.2159 0.36703)
						(xy -0.21209 0.37719) (xy -0.20701 0.38735) (xy -0.2032 0.39624) (xy -0.19812 0.4064) (xy -0.17272 0.44196)
						(xy -0.1651 0.44958) (xy -0.1651 0.7366) (xy -0.16256 0.76835) (xy -0.1524 0.8001) (xy -0.13716 0.82804)
						(xy -0.11684 0.85344) (xy -0.09144 0.87376) (xy -0.0635 0.889) (xy -0.03175 0.89916) (xy 0 0.9017)
						(xy 0.03175 0.89916) (xy 0.0635 0.889) (xy 0.09144 0.87376) (xy 0.11684 0.85344) (xy 0.13716 0.82804)
						(xy 0.1524 0.8001) (xy 0.16256 0.76835) (xy 0.1651 0.7366) (xy 0.1651 0.44958) (xy 0.17272 0.44196)
						(xy 0.19812 0.4064) (xy 0.2032 0.39624) (xy 0.20701 0.38735) (xy 0.21209 0.37719) (xy 0.2159 0.36703)
						(xy 0.21844 0.35687) (xy 0.22225 0.34544) (xy 0.22352 0.33528) (xy 0.22606 0.32512) (xy 0.22733 0.31369)
						(xy 0.22733 0.30353) (xy 0.2286 0.2921) (xy 0.22733 0.28067) (xy 0.22733 0.27051) (xy 0.22606 0.25908)
						(xy 0.22352 0.24892) (xy 0.22225 0.23876) (xy 0.21844 0.22733) (xy 0.2159 0.21717) (xy 0.21209 0.20701)
						(xy 0.20701 0.19685) (xy 0.2032 0.18796) (xy 0.19812 0.1778) (xy 0.17272 0.14224) (xy 0.1651 0.13462)
						(xy 0.1651 -0.7366) (xy 0.16256 -0.76835) (xy 0.1524 -0.8001) (xy 0.13716 -0.82804) (xy 0.11684 -0.85344)
						(xy 0.09144 -0.87376) (xy 0.0635 -0.889) (xy 0.03175 -0.89916)
					)
					(width 0)
					(fill yes)
				)
			)
		)
	)
)
